(kicad_pcb
	(version 20260206)
	(generator "pcbnew")
	(generator_version "10.0")
	(general
		(thickness 1.6)
		(legacy_teardrops no)
	)
	(paper "A4")
	(title_block
		(title "Bryce Canyon_F.DPB_16315-1-OCP.brd")
		(comment 1 "Bryce Canyon / footprints 681-683 of 2223")
	)
	(layers
		(0 "F.Cu" signal "TOP")
		(4 "In1.Cu" signal "L2GND")
		(6 "In2.Cu" signal "L3")
		(8 "In3.Cu" signal "L4GND")
		(10 "In4.Cu" signal "L5")
		(12 "In5.Cu" signal "L6VCC")
		(14 "In6.Cu" signal "L7VCC")
		(16 "In7.Cu" signal "L8")
		(18 "In8.Cu" signal "L9GND")
		(20 "In9.Cu" signal "L10")
		(22 "In10.Cu" signal "L11GND")
		(2 "B.Cu" signal "BOTTOM")
		(9 "F.Adhes" user "F.Adhesive")
		(11 "B.Adhes" user "B.Adhesive")
		(13 "F.Paste" user "Package Geometry/Pastemask Top")
		(15 "B.Paste" user "Package Geometry/Pastemask Bottom")
		(5 "F.SilkS" user "Ref Des/Silkscreen Top")
		(7 "B.SilkS" user "Ref Des/Silkscreen Bottom")
		(1 "F.Mask" user "Board Geometry/Soldermask Top")
		(3 "B.Mask" user "Board Geometry/Soldermask Bottom")
		(17 "Dwgs.User" user "User.Drawings")
		(19 "Cmts.User" user "User.Comments")
		(21 "Eco1.User" user "User.Eco1")
		(23 "Eco2.User" user "User.Eco2")
		(25 "Edge.Cuts" user "Board Geometry/Outline")
		(27 "Margin" user)
		(31 "F.CrtYd" user "Package Geometry/Place Bound Top")
		(29 "B.CrtYd" user "Package Geometry/Place Bound Bottom")
		(35 "F.Fab" user "Ref Des/Assembly Top")
		(33 "B.Fab" user "Ref Des/Assembly Bottom")
	)
	(footprint ""
		(layer "F.Cu")
		(at 122.849894 -172.909992 -90)
		(property "Reference" "HDDSAS15"
			(at 0 0 270)
			(layer "F.SilkS")
			(hide yes)
			(effects
				(font
					(size 1.27 1.27)
				)
			)
		)
		(property "Value" "SKT-SAS15P-14P-45-GP"
			(at -20.7645 -8.9789 270)
			(unlocked yes)
			(layer "F.Fab")
			(hide yes)
			(effects
				(font
					(size 1.016 1.016)
					(thickness 0.1524)
				)
			)
		)
		(property "Device Type" "10120818-001C-TRLF"
			(at -20.7645 -10.5029 270)
			(unlocked yes)
			(layer "F.Fab")
			(hide yes)
			(effects
				(font
					(size 1.016 1.016)
					(thickness 0.1524)
				)
			)
		)
		(duplicate_pad_numbers_are_jumpers no)
		(fp_line
			(start 1.651 4.2926)
			(end 1.651 3.0099)
			(stroke
				(width 0.1524)
				(type default)
			)
			(layer "F.SilkS")
		)
		(fp_line
			(start 8.509 4.2926)
			(end 1.651 4.2926)
			(stroke
				(width 0.1524)
				(type default)
			)
			(layer "F.SilkS")
		)
		(fp_line
			(start -23.4188 3.0099)
			(end -23.4188 -3.2512)
			(stroke
				(width 0.1524)
				(type default)
			)
			(layer "F.SilkS")
		)
		(fp_line
			(start 1.651 3.0099)
			(end -23.4188 3.0099)
			(stroke
				(width 0.1524)
				(type default)
			)
			(layer "F.SilkS")
		)
		(fp_line
			(start 8.509 3.0099)
			(end 8.509 4.2926)
			(stroke
				(width 0.1524)
				(type default)
			)
			(layer "F.SilkS")
		)
		(fp_line
			(start 23.4188 3.0099)
			(end 8.509 3.0099)
			(stroke
				(width 0.1524)
				(type default)
			)
			(layer "F.SilkS")
		)
		(fp_line
			(start -23.4188 -3.2512)
			(end 23.4188 -3.2512)
			(stroke
				(width 0.1524)
				(type default)
			)
			(layer "F.SilkS")
		)
		(fp_line
			(start 23.4188 -3.2512)
			(end 23.4188 3.0099)
			(stroke
				(width 0.1524)
				(type default)
			)
			(layer "F.SilkS")
		)
		(fp_line
			(start 15.5067 -3.3401)
			(end 16.2687 -3.3401)
			(stroke
				(width 0.3302)
				(type default)
			)
			(layer "F.SilkS")
		)
		(fp_poly
			(pts
				(xy 15.868904 -3.230372) (xy 16.503904 -3.865372) (xy 15.233904 -3.865372)
			)
			(stroke
				(width 0)
				(type default)
			)
			(fill yes)
			(layer "F.SilkS")
		)
		(fp_poly
			(pts
				(xy -22.8727 -2.7559) (xy 22.8727 -2.7559) (xy 22.8727 2.7559) (xy 8.255 2.7559) (xy 8.255 3.5179)
				(xy 1.905 3.5179) (xy 1.905 2.7559) (xy -22.8727 2.7559)
			)
			(stroke
				(width 0)
				(type default)
			)
			(fill no)
			(layer "F.CrtYd")
		)
		(fp_poly
			(pts
				(xy 1.397 4.5466) (xy 1.397 3.2639) (xy -23.6728 3.2639) (xy -23.6728 -3.5052) (xy 23.6728 -3.5052)
				(xy 23.6728 -0.00635) (xy 22.8727 -0.00635) (xy 22.8727 -2.7559) (xy -22.8727 -2.7559) (xy -22.8727 2.7559)
				(xy 1.905 2.7559) (xy 1.905 3.5179) (xy 8.255 3.5179) (xy 8.255 2.7559) (xy 22.8727 2.7559) (xy 22.8727 0.00635)
				(xy 23.6728 0.00635) (xy 23.6728 3.2639) (xy 8.763 3.2639) (xy 8.763 4.5466)
			)
			(stroke
				(width 0)
				(type default)
			)
			(fill no)
			(layer "F.CrtYd")
		)
		(fp_poly
			(pts
				(xy 1.397 4.5466) (xy 1.397 3.2639) (xy -23.6728 3.2639) (xy -23.6728 -3.5052) (xy 23.6728 -3.5052)
				(xy 23.6728 3.2639) (xy 8.763 3.2639) (xy 8.763 4.5466)
			)
			(stroke
				(width 0)
				(type default)
			)
			(fill no)
			(layer "F.Fab")
		)
		(pad "" np_thru_hole circle
			(at -18.874994 0 270)
			(size 0.254 0.254)
			(drill 1.3462)
			(layers "*.Cu" "*.Mask")
			(clearance 0.9017)
			(thermal_gap 0.9017)
		)
		(pad "" np_thru_hole circle
			(at 18.874994 0 270)
			(size 0.254 0.254)
			(drill 0.9398)
			(layers "*.Cu" "*.Mask")
			(clearance 0.6985)
			(thermal_gap 0.6985)
		)
		(pad "G1" smd rect
			(at 21.874988 0 270)
			(size 2.5908 2.5908)
			(layers "F.Cu" "F.Mask" "F.Paste")
			(net "GND")
		)
		(pad "G2" smd rect
			(at -21.874988 0 270)
			(size 2.5908 2.5908)
			(layers "F.Cu" "F.Mask" "F.Paste")
			(net "GND")
		)
		(pad "P1" smd rect
			(at 1.905 -1.82499 270)
			(size 0.6096 2.3622)
			(layers "F.Cu" "F.Mask" "F.Paste")
			(net "Net_2141")
		)
		(pad "P2" smd rect
			(at 0.635 -1.82499 270)
			(size 0.6096 2.3622)
			(layers "F.Cu" "F.Mask" "F.Paste")
			(net "Net_2142")
		)
		(pad "P3" smd rect
			(at -0.635 -1.82499 270)
			(size 0.6096 2.3622)
			(layers "F.Cu" "F.Mask" "F.Paste")
			(net "Net_2143")
		)
		(pad "P4" smd rect
			(at -1.905 -1.82499 270)
			(size 0.6096 2.3622)
			(layers "F.Cu" "F.Mask" "F.Paste")
			(net "GND")
		)
		(pad "P5" smd rect
			(at -3.175 -1.82499 270)
			(size 0.6096 2.3622)
			(layers "F.Cu" "F.Mask" "F.Paste")
			(net "HDD_PRSNT_15")
		)
		(pad "P6" smd rect
			(at -4.445 -1.82499 270)
			(size 0.6096 2.3622)
			(layers "F.Cu" "F.Mask" "F.Paste")
			(net "GND")
		)
		(pad "P7" smd rect
			(at -5.715 -1.82499 270)
			(size 0.6096 2.3622)
			(layers "F.Cu" "F.Mask" "F.Paste")
			(net "5V_PRE_15")
		)
		(pad "P8" smd rect
			(at -6.985 -1.82499 270)
			(size 0.6096 2.3622)
			(layers "F.Cu" "F.Mask" "F.Paste")
			(net "P5V_HDD15")
		)
		(pad "P9" smd rect
			(at -8.255 -1.82499 270)
			(size 0.6096 2.3622)
			(layers "F.Cu" "F.Mask" "F.Paste")
			(net "P5V_HDD15")
		)
		(pad "P10" smd rect
			(at -9.525 -1.82499 270)
			(size 0.6096 2.3622)
			(layers "F.Cu" "F.Mask" "F.Paste")
			(net "GND")
		)
		(pad "P11" smd rect
			(at -10.795 -1.82499 270)
			(size 0.6096 2.3622)
			(layers "F.Cu" "F.Mask" "F.Paste")
			(net "ACT_HDD_15")
		)
		(pad "P12" smd rect
			(at -12.065 -1.82499 270)
			(size 0.6096 2.3622)
			(layers "F.Cu" "F.Mask" "F.Paste")
			(net "GND")
		)
		(pad "P13" smd rect
			(at -13.335 -1.82499 270)
			(size 0.6096 2.3622)
			(layers "F.Cu" "F.Mask" "F.Paste")
			(net "12V_PRE_15")
		)
		(pad "P14" smd rect
			(at -14.605 -1.82499 270)
			(size 0.6096 2.3622)
			(layers "F.Cu" "F.Mask" "F.Paste")
			(net "P12V_HDD15")
		)
		(pad "P15" smd rect
			(at -15.875 -1.82499 270)
			(size 0.6096 2.3622)
			(layers "F.Cu" "F.Mask" "F.Paste")
			(net "P12V_HDD15")
		)
		(pad "S1" smd rect
			(at 15.875 -1.82499 270)
			(size 0.6096 2.3622)
			(layers "F.Cu" "F.Mask" "F.Paste")
			(net "GND")
		)
		(pad "S2" smd rect
			(at 14.605 -1.82499 270)
			(size 0.6096 2.3622)
			(layers "F.Cu" "F.Mask" "F.Paste")
			(net "SAS_HDD_RX_P15")
		)
		(pad "S3" smd rect
			(at 13.335 -1.82499 270)
			(size 0.6096 2.3622)
			(layers "F.Cu" "F.Mask" "F.Paste")
			(net "SAS_HDD_RX_N15")
		)
		(pad "S4" smd rect
			(at 12.065 -1.82499 270)
			(size 0.6096 2.3622)
			(layers "F.Cu" "F.Mask" "F.Paste")
			(net "GND")
		)
		(pad "S5" smd rect
			(at 10.795 -1.82499 270)
			(size 0.6096 2.3622)
			(layers "F.Cu" "F.Mask" "F.Paste")
			(net "PHY_DRV_A_TO_SCC_A_15_DN")
		)
		(pad "S6" smd rect
			(at 9.525 -1.82499 270)
			(size 0.6096 2.3622)
			(layers "F.Cu" "F.Mask" "F.Paste")
			(net "PHY_DRV_A_TO_SCC_A_15_DP")
		)
		(pad "S7" smd rect
			(at 8.255 -1.82499 270)
			(size 0.6096 2.3622)
			(layers "F.Cu" "F.Mask" "F.Paste")
			(net "GND")
		)
		(pad "S8" smd rect
			(at 7.480046 2.845054 270)
			(size 0.508 2.3622)
			(layers "F.Cu" "F.Mask" "F.Paste")
			(net "GND")
		)
		(pad "S9" smd rect
			(at 6.679946 2.845054 270)
			(size 0.508 2.3622)
			(layers "F.Cu" "F.Mask" "F.Paste")
			(net "Net_452")
		)
		(pad "S10" smd rect
			(at 5.8801 2.845054 270)
			(size 0.508 2.3622)
			(layers "F.Cu" "F.Mask" "F.Paste")
			(net "Net_344")
		)
		(pad "S11" smd rect
			(at 5.08 2.845054 270)
			(size 0.508 2.3622)
			(layers "F.Cu" "F.Mask" "F.Paste")
			(net "GND")
		)
		(pad "S12" smd rect
			(at 4.2799 2.845054 270)
			(size 0.508 2.3622)
			(layers "F.Cu" "F.Mask" "F.Paste")
			(net "Net_380")
		)
		(pad "S13" smd rect
			(at 3.480054 2.845054 270)
			(size 0.508 2.3622)
			(layers "F.Cu" "F.Mask" "F.Paste")
			(net "Net_416")
		)
		(pad "S14" smd rect
			(at 2.679954 2.845054 270)
			(size 0.508 2.3622)
			(layers "F.Cu" "F.Mask" "F.Paste")
			(net "GND")
		)
		(zone
			(layer "F.Cu")
			(hatch none 0.5)
			(connect_pads
				(clearance 0)
			)
			(min_thickness 0.25)
			(keepout
				(tracks allowed)
				(vias not_allowed)
				(pads allowed)
				(copperpour not_allowed)
				(footprints allowed)
			)
			(placement
				(enabled no)
				(sheetname "")
			)
			(fill
				(thermal_gap 0.5)
				(thermal_bridge_width 0.5)
				(island_removal_mode 0)
			)
			(polygon
				(pts
					(xy 126.507494 -189.648592) (xy 119.433594 -189.648592) (xy 119.433594 -196.582792) (xy 120.538494 -196.582792)
					(xy 120.538494 -192.467992) (xy 125.161294 -192.467992) (xy 125.161294 -196.582792) (xy 126.507494 -196.582792)
				)
			)
		)
		(zone
			(layer "F.Cu")
			(hatch none 0.5)
			(connect_pads
				(clearance 0)
			)
			(min_thickness 0.25)
			(keepout
				(tracks not_allowed)
				(vias allowed)
				(pads allowed)
				(copperpour not_allowed)
				(footprints allowed)
			)
			(placement
				(enabled no)
				(sheetname "")
			)
			(fill
				(thermal_gap 0.5)
				(thermal_bridge_width 0.5)
				(island_removal_mode 0)
			)
			(polygon
				(pts
					(xy 126.507494 -189.648592) (xy 119.433594 -189.648592) (xy 119.433594 -196.582792) (xy 120.538494 -196.582792)
					(xy 120.538494 -192.467992) (xy 125.161294 -192.467992) (xy 125.161294 -196.582792) (xy 126.507494 -196.582792)
				)
			)
		)
		(zone
			(layer "F.Cu")
			(hatch none 0.5)
			(connect_pads
				(clearance 0)
			)
			(min_thickness 0.25)
			(keepout
				(tracks not_allowed)
				(vias allowed)
				(pads allowed)
				(copperpour not_allowed)
				(footprints allowed)
			)
			(placement
				(enabled no)
				(sheetname "")
			)
			(fill
				(thermal_gap 0.5)
				(thermal_bridge_width 0.5)
				(island_removal_mode 0)
			)
			(polygon
				(pts
					(xy 126.507494 -156.171392) (xy 119.433594 -156.171392) (xy 119.433594 -149.237192) (xy 120.538494 -149.237192)
					(xy 120.538494 -153.351992) (xy 125.161294 -153.351992) (xy 125.161294 -149.237192) (xy 126.507494 -149.237192)
				)
			)
		)
		(zone
			(layer "F.Cu")
			(hatch none 0.5)
			(connect_pads
				(clearance 0)
			)
			(min_thickness 0.25)
			(keepout
				(tracks allowed)
				(vias not_allowed)
				(pads allowed)
				(copperpour not_allowed)
				(footprints allowed)
			)
			(placement
				(enabled no)
				(sheetname "")
			)
			(fill
				(thermal_gap 0.5)
				(thermal_bridge_width 0.5)
				(island_removal_mode 0)
			)
			(polygon
				(pts
					(xy 126.507494 -156.171392) (xy 119.433594 -156.171392) (xy 119.433594 -149.237192) (xy 120.538494 -149.237192)
					(xy 120.538494 -153.351992) (xy 125.161294 -153.351992) (xy 125.161294 -149.237192) (xy 126.507494 -149.237192)
				)
			)
		)
		(zone
			(layers "F.Cu" "B.Cu" "In1.Cu" "In2.Cu" "In3.Cu" "In4.Cu" "In5.Cu" "In6.Cu"
				"In7.Cu" "In8.Cu" "In9.Cu" "In10.Cu"
			)
			(hatch none 0.5)
			(connect_pads
				(clearance 0)
			)
			(min_thickness 0.25)
			(keepout
				(tracks not_allowed)
				(vias allowed)
				(pads allowed)
				(copperpour not_allowed)
				(footprints allowed)
			)
			(placement
				(enabled no)
				(sheetname "")
			)
			(fill
				(thermal_gap 0.5)
				(thermal_bridge_width 0.5)
				(island_removal_mode 0)
			)
			(polygon
				(pts
					(arc
						(start 123.624594 -154.034998)
						(mid 122.075194 -154.034998)
						(end 123.624594 -154.034998)
					)
				)
			)
		)
		(zone
			(layers "F.Cu" "B.Cu" "In1.Cu" "In2.Cu" "In3.Cu" "In4.Cu" "In5.Cu" "In6.Cu"
				"In7.Cu" "In8.Cu" "In9.Cu" "In10.Cu"
			)
			(hatch none 0.5)
			(connect_pads
				(clearance 0)
			)
			(min_thickness 0.25)
			(keepout
				(tracks not_allowed)
				(vias allowed)
				(pads allowed)
				(copperpour not_allowed)
				(footprints allowed)
			)
			(placement
				(enabled no)
				(sheetname "")
			)
			(fill
				(thermal_gap 0.5)
				(thermal_bridge_width 0.5)
				(island_removal_mode 0)
			)
			(polygon
				(pts
					(arc
						(start 123.827794 -191.784986)
						(mid 121.871994 -191.784986)
						(end 123.827794 -191.784986)
					)
				)
			)
		)
	)
	(footprint ""
		(layer "F.Cu")
		(at 367.858294 -132.088636)
		(property "Reference" "R1093"
			(at 0 0 0)
			(layer "F.SilkS")
			(hide yes)
			(effects
				(font
					(size 1.27 1.27)
				)
			)
		)
		(property "Value" "62KR2F-GP"
			(at 0.064008 -3.993896 0)
			(unlocked yes)
			(layer "F.Fab")
			(hide yes)
			(effects
				(font
					(size 1.016 1.016)
					(thickness 0.1524)
				)
			)
		)
		(property "Device Type" "R402H16"
			(at 0.064008 -5.517896 0)
			(unlocked yes)
			(layer "F.Fab")
			(hide yes)
			(effects
				(font
					(size 1.016 1.016)
					(thickness 0.1524)
				)
			)
		)
		(duplicate_pad_numbers_are_jumpers no)
		(fp_line
			(start -0.508 -0.9398)
			(end -0.508 0.9398)
			(stroke
				(width 0.1524)
				(type default)
			)
			(layer "F.SilkS")
		)
		(fp_line
			(start 0.508 -0.9398)
			(end -0.508 -0.9398)
			(stroke
				(width 0.1524)
				(type default)
			)
			(layer "F.SilkS")
		)
		(fp_rect
			(start -0.508 0.9398)
			(end 0.508 -0.9398)
			(stroke
				(width 0)
				(type default)
			)
			(fill no)
			(layer "F.CrtYd")
		)
		(fp_rect
			(start -0.508 0.9398)
			(end 0.508 -0.9398)
			(stroke
				(width 0)
				(type default)
			)
			(fill no)
			(layer "F.Fab")
		)
		(pad "1" smd custom
			(at 0 -0.4445)
			(size 0.1397 0.1397)
			(layers "F.Cu" "F.Mask" "F.Paste")
			(net "MB1_ISET_R")
			(options
				(clearance outline)
				(anchor circle)
			)
			(primitives
				(gr_poly
					(pts
						(arc
							(start -0.1778 -0.2794)
							(mid -0.249642 -0.249642)
							(end -0.2794 -0.1778)
						)
						(arc
							(start -0.2794 0.1778)
							(mid -0.249642 0.249642)
							(end -0.1778 0.2794)
						)
						(arc
							(start 0.1778 0.2794)
							(mid 0.249642 0.249642)
							(end 0.2794 0.1778)
						)
						(arc
							(start 0.2794 -0.1778)
							(mid 0.249642 -0.249642)
							(end 0.1778 -0.2794)
						)
					)
					(width 0)
					(fill yes)
				)
			)
		)
		(pad "2" smd custom
			(at 0 0.4445)
			(size 0.1397 0.1397)
			(layers "F.Cu" "F.Mask" "F.Paste")
			(net "AGND_CURRENT_MONOB")
			(options
				(clearance outline)
				(anchor circle)
			)
			(primitives
				(gr_poly
					(pts
						(arc
							(start -0.1778 -0.2794)
							(mid -0.249642 -0.249642)
							(end -0.2794 -0.1778)
						)
						(arc
							(start -0.2794 0.1778)
							(mid -0.249642 0.249642)
							(end -0.1778 0.2794)
						)
						(arc
							(start 0.1778 0.2794)
							(mid 0.249642 0.249642)
							(end 0.2794 0.1778)
						)
						(arc
							(start 0.2794 -0.1778)
							(mid 0.249642 -0.249642)
							(end 0.1778 -0.2794)
						)
					)
					(width 0)
					(fill yes)
				)
			)
		)
	)
	(footprint ""
		(layer "F.Cu")
		(at 463.0039 -62.016894)
		(property "Reference" "Q206"
			(at 0 0 0)
			(layer "F.SilkS")
			(hide yes)
			(effects
				(font
					(size 1.27 1.27)
				)
			)
		)
		(property "Value" "AO4407AL-GP"
			(at -3.707384 -1.5367 0)
			(unlocked yes)
			(layer "F.Fab")
			(hide yes)
			(effects
				(font
					(size 1.016 1.016)
					(thickness 0.1524)
				)
			)
		)
		(property "Device Type" "SOIC8H69"
			(at -3.707384 -3.0607 0)
			(unlocked yes)
			(layer "F.Fab")
			(hide yes)
			(effects
				(font
					(size 1.016 1.016)
					(thickness 0.1524)
				)
			)
		)
		(duplicate_pad_numbers_are_jumpers no)
		(fp_line
			(start -2.7432 -1.4224)
			(end -2.7432 1.4224)
			(stroke
				(width 0.1524)
				(type default)
			)
			(layer "F.SilkS")
		)
		(fp_line
			(start -2.7432 1.4224)
			(end -2.6416 1.4224)
			(stroke
				(width 0.1524)
				(type default)
			)
			(layer "F.SilkS")
		)
		(fp_line
			(start -2.7432 1.4224)
			(end 2.1336 1.4224)
			(stroke
				(width 0.1524)
				(type default)
			)
			(layer "F.SilkS")
		)
		(fp_line
			(start -2.7178 -0.508)
			(end -2.1844 -0.0508)
			(stroke
				(width 0.1524)
				(type default)
			)
			(layer "F.SilkS")
		)
		(fp_line
			(start -2.6289 3.4417)
			(end -2.6289 1.4732)
			(stroke
				(width 0.381)
				(type default)
			)
			(layer "F.SilkS")
		)
		(fp_line
			(start -2.1844 -0.0508)
			(end -2.7178 0.508)
			(stroke
				(width 0.1524)
				(type default)
			)
			(layer "F.SilkS")
		)
		(fp_line
			(start 2.1336 -1.4224)
			(end -2.7432 -1.4224)
			(stroke
				(width 0.1524)
				(type default)
			)
			(layer "F.SilkS")
		)
		(fp_line
			(start 2.1336 1.4224)
			(end 2.1336 -1.4224)
			(stroke
				(width 0.1524)
				(type default)
			)
			(layer "F.SilkS")
		)
		(fp_poly
			(pts
				(xy -2.2098 -1.4224) (xy -2.2098 1.4224) (xy 2.2098 1.4224) (xy 2.2098 -1.4224)
			)
			(stroke
				(width 0)
				(type default)
			)
			(fill yes)
			(layer "F.SilkS")
		)
		(fp_rect
			(start -2.450084 2.999994)
			(end 2.450084 -2.999994)
			(stroke
				(width 0)
				(type default)
			)
			(fill no)
			(layer "F.CrtYd")
		)
		(fp_poly
			(pts
				(xy -2.8194 3.6322) (xy -2.8194 -3.6322) (xy 2.8194 -3.6322) (xy 2.8194 1.18364) (xy 2.450084 1.18364)
				(xy 2.450084 -2.999994) (xy -2.450084 -2.999994) (xy -2.450084 2.999994) (xy 2.450084 2.999994)
				(xy 2.450084 1.18618) (xy 2.8194 1.18618) (xy 2.8194 3.6322)
			)
			(stroke
				(width 0)
				(type default)
			)
			(fill no)
			(layer "F.CrtYd")
		)
		(fp_rect
			(start -2.8194 3.6322)
			(end 2.8194 -3.6322)
			(stroke
				(width 0)
				(type default)
			)
			(fill no)
			(layer "F.Fab")
		)
		(pad "1" smd rect
			(at -1.905 2.54)
			(size 0.635 1.651)
			(layers "F.Cu" "F.Mask" "F.Paste")
			(net "P12V_A")
		)
		(pad "2" smd rect
			(at -0.635 2.54)
			(size 0.635 1.651)
			(layers "F.Cu" "F.Mask" "F.Paste")
			(net "P12V_A")
		)
		(pad "3" smd rect
			(at 0.635 2.54)
			(size 0.635 1.651)
			(layers "F.Cu" "F.Mask" "F.Paste")
			(net "P12V_A")
		)
		(pad "4" smd rect
			(at 1.905 2.54)
			(size 0.635 1.651)
			(layers "F.Cu" "F.Mask" "F.Paste")
			(net "SW_HDD_N34")
		)
		(pad "5" smd rect
			(at 1.905 -2.54)
			(size 0.635 1.651)
			(layers "F.Cu" "F.Mask" "F.Paste")
			(net "P12V_HDD34")
		)
		(pad "6" smd rect
			(at 0.635 -2.54)
			(size 0.635 1.651)
			(layers "F.Cu" "F.Mask" "F.Paste")
			(net "P12V_HDD34")
		)
		(pad "7" smd rect
			(at -0.635 -2.54)
			(size 0.635 1.651)
			(layers "F.Cu" "F.Mask" "F.Paste")
			(net "P12V_HDD34")
		)
		(pad "8" smd rect
			(at -1.905 -2.54)
			(size 0.635 1.651)
			(layers "F.Cu" "F.Mask" "F.Paste")
			(net "P12V_HDD34")
		)
	)
)
